(kicad_pcb
	(version 20260206)
	(generator "pcbnew")
	(generator_version "10.0")
	(general
		(thickness 1.6)
		(legacy_teardrops no)
	)
	(paper "A4")
	(title_block
		(title "Bryce Canyon_IOM_M2_16342-2_OCP.brd")
		(comment 1 "Bryce Canyon / footprints 560-565 of 1146")
	)
	(layers
		(0 "F.Cu" signal "TOP")
		(4 "In1.Cu" signal "L2GND")
		(6 "In2.Cu" signal "L3")
		(8 "In3.Cu" signal "L4VCC")
		(10 "In4.Cu" signal "L5VCC")
		(12 "In5.Cu" signal "L6")
		(14 "In6.Cu" signal "L7GND")
		(2 "B.Cu" signal "BOTTOM")
		(9 "F.Adhes" user "F.Adhesive")
		(11 "B.Adhes" user "B.Adhesive")
		(13 "F.Paste" user "Package Geometry/Pastemask Top")
		(15 "B.Paste" user "Package Geometry/Pastemask Bottom")
		(5 "F.SilkS" user "Ref Des/Silkscreen Top")
		(7 "B.SilkS" user "Ref Des/Silkscreen Bottom")
		(1 "F.Mask" user "Board Geometry/Soldermask Top")
		(3 "B.Mask" user "Board Geometry/Soldermask Bottom")
		(17 "Dwgs.User" user "User.Drawings")
		(19 "Cmts.User" user "User.Comments")
		(21 "Eco1.User" user "User.Eco1")
		(23 "Eco2.User" user "User.Eco2")
		(25 "Edge.Cuts" user "Board Geometry/Outline")
		(27 "Margin" user)
		(31 "F.CrtYd" user "Package Geometry/Place Bound Top")
		(29 "B.CrtYd" user "Package Geometry/Place Bound Bottom")
		(35 "F.Fab" user "Ref Des/Assembly Top")
		(33 "B.Fab" user "Ref Des/Assembly Bottom")
	)
	(footprint ""
		(layer "F.Cu")
		(at 95.1484 -148.6154)
		(property "Reference" "R41"
			(at 0 0 0)
			(layer "F.SilkS")
			(hide yes)
			(effects
				(font
					(size 1.27 1.27)
				)
			)
		)
		(property "Value" "4K7R2F-GP"
			(at 0.064008 -3.993896 0)
			(unlocked yes)
			(layer "F.Fab")
			(hide yes)
			(effects
				(font
					(size 1.016 1.016)
					(thickness 0.1524)
				)
			)
		)
		(property "Device Type" "R402H16"
			(at 0.064008 -5.517896 0)
			(unlocked yes)
			(layer "F.Fab")
			(hide yes)
			(effects
				(font
					(size 1.016 1.016)
					(thickness 0.1524)
				)
			)
		)
		(duplicate_pad_numbers_are_jumpers no)
		(fp_line
			(start -0.508 -0.9398)
			(end -0.508 0.9398)
			(stroke
				(width 0.1524)
				(type default)
			)
			(layer "F.SilkS")
		)
		(fp_line
			(start 0.508 -0.9398)
			(end -0.508 -0.9398)
			(stroke
				(width 0.1524)
				(type default)
			)
			(layer "F.SilkS")
		)
		(fp_rect
			(start -0.508 0.9398)
			(end 0.508 -0.9398)
			(stroke
				(width 0)
				(type default)
			)
			(fill no)
			(layer "F.CrtYd")
		)
		(fp_rect
			(start -0.508 0.9398)
			(end 0.508 -0.9398)
			(stroke
				(width 0)
				(type default)
			)
			(fill no)
			(layer "F.Fab")
		)
		(pad "1" smd custom
			(at 0 -0.4445)
			(size 0.1397 0.1397)
			(layers "F.Cu" "F.Mask" "F.Paste")
			(net "USB_EN_2")
			(options
				(clearance outline)
				(anchor circle)
			)
			(primitives
				(gr_poly
					(pts
						(arc
							(start -0.1778 -0.2794)
							(mid -0.249642 -0.249642)
							(end -0.2794 -0.1778)
						)
						(arc
							(start -0.2794 0.1778)
							(mid -0.249642 0.249642)
							(end -0.1778 0.2794)
						)
						(arc
							(start 0.1778 0.2794)
							(mid 0.249642 0.249642)
							(end 0.2794 0.1778)
						)
						(arc
							(start 0.2794 -0.1778)
							(mid 0.249642 -0.249642)
							(end 0.1778 -0.2794)
						)
					)
					(width 0)
					(fill yes)
				)
			)
		)
		(pad "2" smd custom
			(at 0 0.4445)
			(size 0.1397 0.1397)
			(layers "F.Cu" "F.Mask" "F.Paste")
			(net "GND")
			(options
				(clearance outline)
				(anchor circle)
			)
			(primitives
				(gr_poly
					(pts
						(arc
							(start -0.1778 -0.2794)
							(mid -0.249642 -0.249642)
							(end -0.2794 -0.1778)
						)
						(arc
							(start -0.2794 0.1778)
							(mid -0.249642 0.249642)
							(end -0.1778 0.2794)
						)
						(arc
							(start 0.1778 0.2794)
							(mid 0.249642 0.249642)
							(end 0.2794 0.1778)
						)
						(arc
							(start 0.2794 -0.1778)
							(mid 0.249642 -0.249642)
							(end 0.1778 -0.2794)
						)
					)
					(width 0)
					(fill yes)
				)
			)
		)
	)
	(footprint ""
		(layer "F.Cu")
		(at 8.8392 -139.573 90)
		(property "Reference" "R217"
			(at 0 0 90)
			(layer "F.SilkS")
			(hide yes)
			(effects
				(font
					(size 1.27 1.27)
				)
			)
		)
		(property "Value" "120R2F-GP"
			(at 0.064008 -3.993896 90)
			(unlocked yes)
			(layer "F.Fab")
			(hide yes)
			(effects
				(font
					(size 1.016 1.016)
					(thickness 0.1524)
				)
			)
		)
		(property "Device Type" "R402H16"
			(at 0.064008 -5.517896 90)
			(unlocked yes)
			(layer "F.Fab")
			(hide yes)
			(effects
				(font
					(size 1.016 1.016)
					(thickness 0.1524)
				)
			)
		)
		(duplicate_pad_numbers_are_jumpers no)
		(fp_line
			(start 0.508 -0.9398)
			(end -0.508 -0.9398)
			(stroke
				(width 0.1524)
				(type default)
			)
			(layer "F.SilkS")
		)
		(fp_line
			(start -0.508 -0.9398)
			(end -0.508 0.9398)
			(stroke
				(width 0.1524)
				(type default)
			)
			(layer "F.SilkS")
		)
		(fp_rect
			(start -0.508 0.9398)
			(end 0.508 -0.9398)
			(stroke
				(width 0)
				(type default)
			)
			(fill no)
			(layer "F.CrtYd")
		)
		(fp_rect
			(start -0.508 0.9398)
			(end 0.508 -0.9398)
			(stroke
				(width 0)
				(type default)
			)
			(fill no)
			(layer "F.Fab")
		)
		(pad "1" smd custom
			(at 0 -0.4445 90)
			(size 0.1397 0.1397)
			(layers "F.Cu" "F.Mask" "F.Paste")
			(net "GND")
			(options
				(clearance outline)
				(anchor circle)
			)
			(primitives
				(gr_poly
					(pts
						(arc
							(start -0.1778 -0.2794)
							(mid -0.249642 -0.249642)
							(end -0.2794 -0.1778)
						)
						(arc
							(start -0.2794 0.1778)
							(mid -0.249642 0.249642)
							(end -0.1778 0.2794)
						)
						(arc
							(start 0.1778 0.2794)
							(mid 0.249642 0.249642)
							(end 0.2794 0.1778)
						)
						(arc
							(start 0.2794 -0.1778)
							(mid 0.249642 -0.249642)
							(end 0.1778 -0.2794)
						)
					)
					(width 0)
					(fill yes)
				)
			)
		)
		(pad "2" smd custom
			(at 0 0.4445 90)
			(size 0.1397 0.1397)
			(layers "F.Cu" "F.Mask" "F.Paste")
			(net "MEMBG_0")
			(options
				(clearance outline)
				(anchor circle)
			)
			(primitives
				(gr_poly
					(pts
						(arc
							(start -0.1778 -0.2794)
							(mid -0.249642 -0.249642)
							(end -0.2794 -0.1778)
						)
						(arc
							(start -0.2794 0.1778)
							(mid -0.249642 0.249642)
							(end -0.1778 0.2794)
						)
						(arc
							(start 0.1778 0.2794)
							(mid 0.249642 0.249642)
							(end 0.2794 0.1778)
						)
						(arc
							(start 0.2794 -0.1778)
							(mid 0.249642 -0.249642)
							(end 0.1778 -0.2794)
						)
					)
					(width 0)
					(fill yes)
				)
			)
		)
	)
	(footprint ""
		(layer "F.Cu")
		(at 42.23512 -131.7498 180)
		(property "Reference" "R263"
			(at 0 0 180)
			(layer "F.SilkS")
			(hide yes)
			(effects
				(font
					(size 1.27 1.27)
				)
			)
		)
		(property "Value" "4K7R2F-GP"
			(at 0.064008 -3.993896 180)
			(unlocked yes)
			(layer "F.Fab")
			(hide yes)
			(effects
				(font
					(size 1.016 1.016)
					(thickness 0.1524)
				)
			)
		)
		(property "Device Type" "R402H16"
			(at 0.064008 -5.517896 180)
			(unlocked yes)
			(layer "F.Fab")
			(hide yes)
			(effects
				(font
					(size 1.016 1.016)
					(thickness 0.1524)
				)
			)
		)
		(duplicate_pad_numbers_are_jumpers no)
		(fp_line
			(start 0.508 -0.9398)
			(end -0.508 -0.9398)
			(stroke
				(width 0.1524)
				(type default)
			)
			(layer "F.SilkS")
		)
		(fp_line
			(start -0.508 -0.9398)
			(end -0.508 0.9398)
			(stroke
				(width 0.1524)
				(type default)
			)
			(layer "F.SilkS")
		)
		(fp_rect
			(start -0.508 0.9398)
			(end 0.508 -0.9398)
			(stroke
				(width 0)
				(type default)
			)
			(fill no)
			(layer "F.CrtYd")
		)
		(fp_rect
			(start -0.508 0.9398)
			(end 0.508 -0.9398)
			(stroke
				(width 0)
				(type default)
			)
			(fill no)
			(layer "F.Fab")
		)
		(pad "1" smd custom
			(at 0 -0.4445 180)
			(size 0.1397 0.1397)
			(layers "F.Cu" "F.Mask" "F.Paste")
			(net "P3V3_STBY")
			(options
				(clearance outline)
				(anchor circle)
			)
			(primitives
				(gr_poly
					(pts
						(arc
							(start -0.1778 -0.2794)
							(mid -0.249642 -0.249642)
							(end -0.2794 -0.1778)
						)
						(arc
							(start -0.2794 0.1778)
							(mid -0.249642 0.249642)
							(end -0.1778 0.2794)
						)
						(arc
							(start 0.1778 0.2794)
							(mid 0.249642 0.249642)
							(end 0.2794 0.1778)
						)
						(arc
							(start 0.2794 -0.1778)
							(mid 0.249642 -0.249642)
							(end 0.1778 -0.2794)
						)
					)
					(width 0)
					(fill yes)
				)
			)
		)
		(pad "2" smd custom
			(at 0 0.4445 180)
			(size 0.1397 0.1397)
			(layers "F.Cu" "F.Mask" "F.Paste")
			(net "BMC_GPIOY1")
			(options
				(clearance outline)
				(anchor circle)
			)
			(primitives
				(gr_poly
					(pts
						(arc
							(start -0.1778 -0.2794)
							(mid -0.249642 -0.249642)
							(end -0.2794 -0.1778)
						)
						(arc
							(start -0.2794 0.1778)
							(mid -0.249642 0.249642)
							(end -0.1778 0.2794)
						)
						(arc
							(start 0.1778 0.2794)
							(mid 0.249642 0.249642)
							(end 0.2794 0.1778)
						)
						(arc
							(start 0.2794 -0.1778)
							(mid 0.249642 -0.249642)
							(end 0.1778 -0.2794)
						)
					)
					(width 0)
					(fill yes)
				)
			)
		)
	)
	(footprint ""
		(layer "F.Cu")
		(at 84.709 -29.21 180)
		(property "Reference" "L23"
			(at 0 0 180)
			(layer "F.SilkS")
			(hide yes)
			(effects
				(font
					(size 1.27 1.27)
				)
			)
		)
		(property "Value" "BLM21PG300SN-2GP"
			(at 0.0254 -5.6896 180)
			(unlocked yes)
			(layer "F.Fab")
			(hide yes)
			(effects
				(font
					(size 1.016 1.016)
					(thickness 0.1524)
				)
			)
		)
		(property "Device Type" "L20125H42"
			(at 0.0254 -7.5946 180)
			(unlocked yes)
			(layer "F.Fab")
			(hide yes)
			(effects
				(font
					(size 1.016 1.016)
					(thickness 0.1524)
				)
			)
		)
		(duplicate_pad_numbers_are_jumpers no)
		(fp_line
			(start 0.9144 1.7018)
			(end 0.9144 -1.7018)
			(stroke
				(width 0.1524)
				(type default)
			)
			(layer "F.SilkS")
		)
		(fp_line
			(start 0.9144 -1.7018)
			(end -0.9144 -1.7018)
			(stroke
				(width 0.1524)
				(type default)
			)
			(layer "F.SilkS")
		)
		(fp_line
			(start -0.9144 1.7018)
			(end 0.9144 1.7018)
			(stroke
				(width 0.1524)
				(type default)
			)
			(layer "F.SilkS")
		)
		(fp_line
			(start -0.9144 -1.7018)
			(end -0.9144 1.7018)
			(stroke
				(width 0.1524)
				(type default)
			)
			(layer "F.SilkS")
		)
		(fp_rect
			(start -1.0033 1.778)
			(end 1.0033 -1.778)
			(stroke
				(width 0)
				(type default)
			)
			(fill no)
			(layer "F.CrtYd")
		)
		(fp_poly
			(pts
				(xy -1.0033 -1.778) (xy 1.0033 -1.778) (xy 1.0033 1.778) (xy -1.0033 1.778)
			)
			(stroke
				(width 0)
				(type default)
			)
			(fill no)
			(layer "F.Fab")
		)
		(pad "1" smd rect
			(at 0 -0.9652 180)
			(size 1.397 1.143)
			(layers "F.Cu" "F.Mask" "F.Paste")
			(net "P5V_VBUS_CONN")
		)
		(pad "2" smd rect
			(at 0 0.9652 180)
			(size 1.397 1.143)
			(layers "F.Cu" "F.Mask" "F.Paste")
			(net "P5V_USB")
		)
	)
	(footprint ""
		(layer "F.Cu")
		(at 228.497638 -98.591878 180)
		(property "Reference" "L30"
			(at 0 0 180)
			(layer "F.SilkS")
			(hide yes)
			(effects
				(font
					(size 1.27 1.27)
				)
			)
		)
		(property "Value" "BLM21PG220SN1DGP"
			(at 0.0254 -5.6896 180)
			(unlocked yes)
			(layer "F.Fab")
			(hide yes)
			(effects
				(font
					(size 1.016 1.016)
					(thickness 0.1524)
				)
			)
		)
		(property "Device Type" "L20125H42"
			(at 0.0254 -7.5946 180)
			(unlocked yes)
			(layer "F.Fab")
			(hide yes)
			(effects
				(font
					(size 1.016 1.016)
					(thickness 0.1524)
				)
			)
		)
		(duplicate_pad_numbers_are_jumpers no)
		(fp_line
			(start 0.9144 1.7018)
			(end 0.9144 -1.7018)
			(stroke
				(width 0.1524)
				(type default)
			)
			(layer "F.SilkS")
		)
		(fp_line
			(start 0.9144 -1.7018)
			(end -0.9144 -1.7018)
			(stroke
				(width 0.1524)
				(type default)
			)
			(layer "F.SilkS")
		)
		(fp_line
			(start -0.9144 1.7018)
			(end 0.9144 1.7018)
			(stroke
				(width 0.1524)
				(type default)
			)
			(layer "F.SilkS")
		)
		(fp_line
			(start -0.9144 -1.7018)
			(end -0.9144 1.7018)
			(stroke
				(width 0.1524)
				(type default)
			)
			(layer "F.SilkS")
		)
		(fp_rect
			(start -1.0033 1.778)
			(end 1.0033 -1.778)
			(stroke
				(width 0)
				(type default)
			)
			(fill no)
			(layer "F.CrtYd")
		)
		(fp_poly
			(pts
				(xy -1.0033 -1.778) (xy 1.0033 -1.778) (xy 1.0033 1.778) (xy -1.0033 1.778)
			)
			(stroke
				(width 0)
				(type default)
			)
			(fill no)
			(layer "F.Fab")
		)
		(pad "1" smd rect
			(at 0 -0.9652 180)
			(size 1.397 1.143)
			(layers "F.Cu" "F.Mask" "F.Paste")
			(net "P12V_STBY")
		)
		(pad "2" smd rect
			(at 0 0.9652 180)
			(size 1.397 1.143)
			(layers "F.Cu" "F.Mask" "F.Paste")
			(net "P12V_STBY_VIN_U81")
		)
	)
	(footprint ""
		(layer "F.Cu")
		(at 124.841 -7.62 -90)
		(property "Reference" "R438"
			(at 0 0 270)
			(layer "F.SilkS")
			(hide yes)
			(effects
				(font
					(size 1.27 1.27)
				)
			)
		)
		(property "Value" "10KR2J-3-GP"
			(at 0.064008 -3.993896 270)
			(unlocked yes)
			(layer "F.Fab")
			(hide yes)
			(effects
				(font
					(size 1.016 1.016)
					(thickness 0.1524)
				)
			)
		)
		(property "Device Type" "R402H16"
			(at 0.064008 -5.517896 270)
			(unlocked yes)
			(layer "F.Fab")
			(hide yes)
			(effects
				(font
					(size 1.016 1.016)
					(thickness 0.1524)
				)
			)
		)
		(duplicate_pad_numbers_are_jumpers no)
		(fp_line
			(start -0.508 -0.9398)
			(end -0.508 0.9398)
			(stroke
				(width 0.1524)
				(type default)
			)
			(layer "F.SilkS")
		)
		(fp_line
			(start 0.508 -0.9398)
			(end -0.508 -0.9398)
			(stroke
				(width 0.1524)
				(type default)
			)
			(layer "F.SilkS")
		)
		(fp_rect
			(start -0.508 0.9398)
			(end 0.508 -0.9398)
			(stroke
				(width 0)
				(type default)
			)
			(fill no)
			(layer "F.CrtYd")
		)
		(fp_rect
			(start -0.508 0.9398)
			(end 0.508 -0.9398)
			(stroke
				(width 0)
				(type default)
			)
			(fill no)
			(layer "F.Fab")
		)
		(pad "1" smd custom
			(at 0 -0.4445 270)
			(size 0.1397 0.1397)
			(layers "F.Cu" "F.Mask" "F.Paste")
			(net "GND")
			(options
				(clearance outline)
				(anchor circle)
			)
			(primitives
				(gr_poly
					(pts
						(arc
							(start -0.1778 -0.2794)
							(mid -0.249642 -0.249642)
							(end -0.2794 -0.1778)
						)
						(arc
							(start -0.2794 0.1778)
							(mid -0.249642 0.249642)
							(end -0.1778 0.2794)
						)
						(arc
							(start 0.1778 0.2794)
							(mid 0.249642 0.249642)
							(end 0.2794 0.1778)
						)
						(arc
							(start 0.2794 -0.1778)
							(mid 0.249642 -0.249642)
							(end 0.1778 -0.2794)
						)
					)
					(width 0)
					(fill yes)
				)
			)
		)
		(pad "2" smd custom
			(at 0 0.4445 270)
			(size 0.1397 0.1397)
			(layers "F.Cu" "F.Mask" "F.Paste")
			(net "MB0_RETRY_R")
			(options
				(clearance outline)
				(anchor circle)
			)
			(primitives
				(gr_poly
					(pts
						(arc
							(start -0.1778 -0.2794)
							(mid -0.249642 -0.249642)
							(end -0.2794 -0.1778)
						)
						(arc
							(start -0.2794 0.1778)
							(mid -0.249642 0.249642)
							(end -0.1778 0.2794)
						)
						(arc
							(start 0.1778 0.2794)
							(mid 0.249642 0.249642)
							(end 0.2794 0.1778)
						)
						(arc
							(start 0.2794 -0.1778)
							(mid 0.249642 -0.249642)
							(end 0.1778 -0.2794)
						)
					)
					(width 0)
					(fill yes)
				)
			)
		)
	)
)
